# S9S_MB_2U (Grand Teton) — schematic netlist excerpt (pin names and nets, part order shuffled) for the footprints in the layout excerpt that follows; sources: Cadence DE-HDL packaged netlist, KiCad conversion of 03242023_DA0F0TMBIJ0_F0T_Motherboard_J_brd_V01_OCP.brd

Q102  MOSFET_NCH_DUAL  PJT138K IC  pkg SOT363XD  page 147
  S1  = GND
  G1  = GPU_BASE_HMC_READY
  D2  = GPU_BASE_HMC_READY_ISO
  S2  = GND
  G2  = GPU_BASE_HMC_READY_N
  D1  = GPU_BASE_HMC_READY_N

PR3960  Q_RES  160K 1% EMPTY  pkg 0402LF  page 192 : A = P12V_AUX ; B = P12V_E1S_UV_0
C151  Q_CAP_DIFFBUS  DIFF BUS_0.22UF 6.3V 20% X6S  pkg C0201  page 178 : \1\ = DMI_CPU0_PCH_TX_C_DN<1> ; \2\ = DMI_CPU0_PCH_TX_DN<1>

(kicad_pcb
	(version 20260206)
	(generator "pcbnew")
	(generator_version "10.0")
	(general
		(thickness 1.6)
		(legacy_teardrops no)
	)
	(paper "A4")
	(title_block
		(title "03242023_DA0F0TMBIJ0_F0T_Motherboard_J_brd_V01_OCP.brd")
		(comment 1 "Grand Teton / footprints 3484-3486 of 6105")
	)
	(layers
		(0 "F.Cu" signal "TOP")
		(4 "In1.Cu" signal "GND")
		(6 "In2.Cu" signal "IN1")
		(8 "In3.Cu" signal "GND1")
		(10 "In4.Cu" signal "IN2")
		(12 "In5.Cu" signal "GND2")
		(14 "In6.Cu" signal "IN3")
		(16 "In7.Cu" signal "GND3")
		(18 "In8.Cu" signal "VCC")
		(20 "In9.Cu" signal "VCC1")
		(22 "In10.Cu" signal "GND4")
		(24 "In11.Cu" signal "IN4")
		(26 "In12.Cu" signal "GND5")
		(28 "In13.Cu" signal "IN5")
		(30 "In14.Cu" signal "GND6")
		(32 "In15.Cu" signal "IN6")
		(34 "In16.Cu" signal "GND7")
		(2 "B.Cu" signal "BOTTOM")
		(9 "F.Adhes" user "F.Adhesive")
		(11 "B.Adhes" user "B.Adhesive")
		(13 "F.Paste" user "Package Geometry/Pastemask Top")
		(15 "B.Paste" user "Package Geometry/Pastemask Bottom")
		(5 "F.SilkS" user "Ref Des/Silkscreen Top")
		(7 "B.SilkS" user "Ref Des/Silkscreen Bottom")
		(1 "F.Mask" user "Board Geometry/Soldermask Top")
		(3 "B.Mask" user "Board Geometry/Soldermask Bottom")
		(17 "Dwgs.User" user "User.Drawings")
		(19 "Cmts.User" user "User.Comments")
		(21 "Eco1.User" user "User.Eco1")
		(23 "Eco2.User" user "User.Eco2")
		(25 "Edge.Cuts" user "Board Geometry/Outline")
		(27 "Margin" user)
		(31 "F.CrtYd" user "Package Geometry/Place Bound Top")
		(29 "B.CrtYd" user "Package Geometry/Place Bound Bottom")
		(35 "F.Fab" user "Ref Des/Assembly Top")
		(33 "B.Fab" user "Ref Des/Assembly Bottom")
	)
	(footprint ""
		(layer "F.Cu")
		(at 173.453552 -420.324534)
		(property "Reference" "Q102"
			(at -1.52908 -1.750568 0)
			(unlocked yes)
			(layer "F.SilkS")
			(effects
				(font
					(size 0.7874 0.5842)
					(thickness 0.1524)
				)
				(justify left)
			)
		)
		(property "Value" ""
			(at 0 0 0)
			(layer "F.Fab")
			(effects
				(font
					(size 1.27 1.27)
				)
			)
		)
		(duplicate_pad_numbers_are_jumpers no)
		(fp_line
			(start -1.332738 -1.100074)
			(end -0.4826 -1.100074)
			(stroke
				(width 0.1524)
				(type default)
			)
			(layer "F.SilkS")
		)
		(fp_line
			(start -1.332738 1.100074)
			(end -1.332738 -1.100074)
			(stroke
				(width 0.1524)
				(type default)
			)
			(layer "F.SilkS")
		)
		(fp_line
			(start -0.4826 -1.100074)
			(end 0 -0.541274)
			(stroke
				(width 0.1524)
				(type default)
			)
			(layer "F.SilkS")
		)
		(fp_line
			(start 0 -0.541274)
			(end 0.4826 -1.100074)
			(stroke
				(width 0.1524)
				(type default)
			)
			(layer "F.SilkS")
		)
		(fp_line
			(start 0.4826 -1.100074)
			(end 1.332738 -1.100074)
			(stroke
				(width 0.1524)
				(type default)
			)
			(layer "F.SilkS")
		)
		(fp_line
			(start 1.332738 -1.100074)
			(end 1.332738 1.100074)
			(stroke
				(width 0.1524)
				(type default)
			)
			(layer "F.SilkS")
		)
		(fp_line
			(start 1.332738 1.100074)
			(end -1.332738 1.100074)
			(stroke
				(width 0.1524)
				(type default)
			)
			(layer "F.SilkS")
		)
		(fp_poly
			(pts
				(xy -2.385568 -1.650746) (xy -1.683512 -1.299718) (xy -2.385568 -0.94869)
			)
			(stroke
				(width 0)
				(type default)
			)
			(fill yes)
			(layer "F.SilkS")
		)
		(fp_line
			(start -0.674878 -1.100074)
			(end 0.674878 -1.100074)
			(stroke
				(width 0.1)
				(type default)
			)
			(layer "F.Fab")
		)
		(fp_line
			(start -0.674878 1.100074)
			(end -0.674878 -1.100074)
			(stroke
				(width 0.1)
				(type default)
			)
			(layer "F.Fab")
		)
		(fp_line
			(start 0.674878 -1.100074)
			(end 0.674878 1.100074)
			(stroke
				(width 0.1)
				(type default)
			)
			(layer "F.Fab")
		)
		(fp_line
			(start 0.674878 1.100074)
			(end -0.674878 1.100074)
			(stroke
				(width 0.1)
				(type default)
			)
			(layer "F.Fab")
		)
		(fp_poly
			(pts
				(xy -2.2352 -0.298958) (xy -2.2352 -1.001014) (xy -1.533144 -0.649986)
			)
			(stroke
				(width 0)
				(type default)
			)
			(fill yes)
			(layer "F.Fab")
		)
		(pad "1" smd rect
			(at -0.94996 -0.649986 90)
			(size 0.4318 0.508)
			(layers "F.Cu" "F.Mask" "F.Paste")
			(net "GND")
		)
		(pad "2" smd rect
			(at -0.94996 0 90)
			(size 0.4318 0.508)
			(layers "F.Cu" "F.Mask" "F.Paste")
			(net "GPU_BASE_HMC_READY")
		)
		(pad "3" smd rect
			(at -0.94996 0.649986 90)
			(size 0.4318 0.508)
			(layers "F.Cu" "F.Mask" "F.Paste")
			(net "GPU_BASE_HMC_READY_ISO")
		)
		(pad "4" smd rect
			(at 0.94996 0.649986 90)
			(size 0.4318 0.508)
			(layers "F.Cu" "F.Mask" "F.Paste")
			(net "GND")
		)
		(pad "5" smd rect
			(at 0.94996 0 90)
			(size 0.4318 0.508)
			(layers "F.Cu" "F.Mask" "F.Paste")
			(net "GPU_BASE_HMC_READY_N")
		)
		(pad "6" smd rect
			(at 0.94996 -0.649986 90)
			(size 0.4318 0.508)
			(layers "F.Cu" "F.Mask" "F.Paste")
			(net "GPU_BASE_HMC_READY_N")
		)
	)
	(footprint ""
		(layer "F.Cu")
		(at 250.30303 -44.979082 -90)
		(property "Reference" "PR3960"
			(at 0 0 270)
			(layer "F.SilkS")
			(hide yes)
			(effects
				(font
					(size 1.27 1.27)
				)
			)
		)
		(property "Value" ""
			(at 0 0 270)
			(layer "F.Fab")
			(effects
				(font
					(size 1.27 1.27)
				)
			)
		)
		(duplicate_pad_numbers_are_jumpers no)
		(fp_line
			(start -0.7874 0.4064)
			(end -0.7874 -0.4064)
			(stroke
				(width 0.1524)
				(type default)
			)
			(layer "F.SilkS")
		)
		(fp_line
			(start 0.7874 0.4064)
			(end -0.7874 0.4064)
			(stroke
				(width 0.1524)
				(type default)
			)
			(layer "F.SilkS")
		)
		(fp_line
			(start -0.7874 -0.4064)
			(end 0.7874 -0.4064)
			(stroke
				(width 0.1524)
				(type default)
			)
			(layer "F.SilkS")
		)
		(fp_line
			(start 0.7874 -0.4064)
			(end 0.7874 0.4064)
			(stroke
				(width 0.1524)
				(type default)
			)
			(layer "F.SilkS")
		)
		(fp_line
			(start -0.67945 0.3048)
			(end -0.67945 -0.305054)
			(stroke
				(width 0.1)
				(type default)
			)
			(layer "F.Fab")
		)
		(fp_line
			(start -0.12065 0.3048)
			(end -0.67945 0.3048)
			(stroke
				(width 0.1)
				(type default)
			)
			(layer "F.Fab")
		)
		(fp_line
			(start 0.120396 0.3048)
			(end 0.120396 0.2794)
			(stroke
				(width 0.1)
				(type default)
			)
			(layer "F.Fab")
		)
		(fp_line
			(start 0.67945 0.3048)
			(end 0.120396 0.3048)
			(stroke
				(width 0.1)
				(type default)
			)
			(layer "F.Fab")
		)
		(fp_line
			(start -0.12065 0.2794)
			(end -0.12065 0.3048)
			(stroke
				(width 0.1)
				(type default)
			)
			(layer "F.Fab")
		)
		(fp_line
			(start 0.120396 0.2794)
			(end -0.12065 0.2794)
			(stroke
				(width 0.1)
				(type default)
			)
			(layer "F.Fab")
		)
		(fp_line
			(start -0.12065 -0.2794)
			(end 0.12065 -0.2794)
			(stroke
				(width 0.1)
				(type default)
			)
			(layer "F.Fab")
		)
		(fp_line
			(start 0.12065 -0.2794)
			(end 0.12065 -0.3048)
			(stroke
				(width 0.1)
				(type default)
			)
			(layer "F.Fab")
		)
		(fp_line
			(start 0.12065 -0.3048)
			(end 0.67945 -0.3048)
			(stroke
				(width 0.1)
				(type default)
			)
			(layer "F.Fab")
		)
		(fp_line
			(start 0.67945 -0.3048)
			(end 0.67945 0.3048)
			(stroke
				(width 0.1)
				(type default)
			)
			(layer "F.Fab")
		)
		(fp_line
			(start -0.67945 -0.305054)
			(end -0.12065 -0.305054)
			(stroke
				(width 0.1)
				(type default)
			)
			(layer "F.Fab")
		)
		(fp_line
			(start -0.12065 -0.305054)
			(end -0.12065 -0.2794)
			(stroke
				(width 0.1)
				(type default)
			)
			(layer "F.Fab")
		)
		(pad "1" smd circle
			(at -0.40005 0 270)
			(size 0 0)
			(layers "F.Cu" "F.Mask" "F.Paste")
			(net "P12V_AUX")
		)
		(pad "2" smd circle
			(at 0.40005 0 270)
			(size 0 0)
			(layers "F.Cu" "F.Mask" "F.Paste")
			(net "P12V_E1S_UV_0")
		)
	)
	(footprint ""
		(layer "F.Cu")
		(at 344.64879 -70.52056 90)
		(property "Reference" "C151"
			(at 0 0 90)
			(layer "F.SilkS")
			(hide yes)
			(effects
				(font
					(size 1.27 1.27)
				)
			)
		)
		(property "Value" ""
			(at 0 0 90)
			(layer "F.Fab")
			(effects
				(font
					(size 1.27 1.27)
				)
			)
		)
		(duplicate_pad_numbers_are_jumpers no)
		(fp_line
			(start 0.299974 -0.150114)
			(end 0.299974 0.150114)
			(stroke
				(width 0.1)
				(type default)
			)
			(layer "F.Fab")
		)
		(fp_line
			(start -0.299974 -0.150114)
			(end 0.299974 -0.150114)
			(stroke
				(width 0.1)
				(type default)
			)
			(layer "F.Fab")
		)
		(fp_line
			(start 0.299974 0.150114)
			(end -0.299974 0.150114)
			(stroke
				(width 0.1)
				(type default)
			)
			(layer "F.Fab")
		)
		(fp_line
			(start -0.299974 0.150114)
			(end -0.299974 -0.150114)
			(stroke
				(width 0.1)
				(type default)
			)
			(layer "F.Fab")
		)
		(pad "1" smd rect
			(at -0.2667 0 90)
			(size 0.3048 0.381)
			(layers "F.Cu" "F.Mask" "F.Paste")
			(net "DMI_CPU0_PCH_TX_C_DN<1>")
		)
		(pad "2" smd rect
			(at 0.2667 0 90)
			(size 0.3048 0.381)
			(layers "F.Cu" "F.Mask" "F.Paste")
			(net "DMI_CPU0_PCH_TX_DN<1>")
		)
	)
)
